(kicad_pcb
	(version 20260206)
	(generator "pcbnew")
	(generator_version "10.0")
	(general
		(thickness 1.6)
		(legacy_teardrops no)
	)
	(paper "A4")
	(title_block
		(title "4HDD Backplane_Layout.brd")
		(comment 1 "Tioga Pass / footprints 78-82 of 97")
	)
	(layers
		(0 "F.Cu" signal "TOP")
		(4 "In1.Cu" signal "L2GND")
		(6 "In2.Cu" signal "L3")
		(8 "In3.Cu" signal "L4")
		(10 "In4.Cu" signal "L5GND")
		(2 "B.Cu" signal "BOTTOM")
		(9 "F.Adhes" user "F.Adhesive")
		(11 "B.Adhes" user "B.Adhesive")
		(13 "F.Paste" user "Package Geometry/Pastemask Top")
		(15 "B.Paste" user "Package Geometry/Pastemask Bottom")
		(5 "F.SilkS" user "Ref Des/Silkscreen Top")
		(7 "B.SilkS" user "Ref Des/Silkscreen Bottom")
		(1 "F.Mask" user "Board Geometry/Soldermask Top")
		(3 "B.Mask" user "Board Geometry/Soldermask Bottom")
		(17 "Dwgs.User" user "User.Drawings")
		(19 "Cmts.User" user "User.Comments")
		(21 "Eco1.User" user "User.Eco1")
		(23 "Eco2.User" user "User.Eco2")
		(25 "Edge.Cuts" user "Board Geometry/Outline")
		(27 "Margin" user)
		(31 "F.CrtYd" user "Package Geometry/Place Bound Top")
		(29 "B.CrtYd" user "Package Geometry/Place Bound Bottom")
		(35 "F.Fab" user "Ref Des/Assembly Top")
		(33 "B.Fab" user "Ref Des/Assembly Bottom")
	)
	(footprint ""
		(layer "B.Cu")
		(at 11.34999 -13.299948 -90)
		(property "Reference" "CN1"
			(at 0 0 90)
			(layer "B.SilkS")
			(hide yes)
			(effects
				(font
					(size 1.27 1.27)
				)
				(justify mirror)
			)
		)
		(property "Value" "SMC-CON15-1-GP"
			(at 9.9568 -1.2573 270)
			(unlocked yes)
			(layer "B.Fab")
			(hide yes)
			(effects
				(font
					(size 1.016 1.016)
					(thickness 0.1524)
				)
				(justify mirror)
			)
		)
		(property "Device Type" "T1M-15-F-SV-L-P"
			(at 9.9568 -2.7813 270)
			(unlocked yes)
			(layer "B.Fab")
			(hide yes)
			(effects
				(font
					(size 1.016 1.016)
					(thickness 0.1524)
				)
				(justify mirror)
			)
		)
		(duplicate_pad_numbers_are_jumpers no)
		(fp_line
			(start -3.7592 2.0574)
			(end 3.7592 2.0574)
			(stroke
				(width 0.1524)
				(type default)
			)
			(layer "B.SilkS")
		)
		(fp_line
			(start 3.7592 2.0574)
			(end 3.7592 1.1684)
			(stroke
				(width 0.1524)
				(type default)
			)
			(layer "B.SilkS")
		)
		(fp_line
			(start -8.9662 1.1684)
			(end -3.7592 1.1684)
			(stroke
				(width 0.1524)
				(type default)
			)
			(layer "B.SilkS")
		)
		(fp_line
			(start -3.7592 1.1684)
			(end -3.7592 2.0574)
			(stroke
				(width 0.1524)
				(type default)
			)
			(layer "B.SilkS")
		)
		(fp_line
			(start 3.7592 1.1684)
			(end 8.9662 1.1684)
			(stroke
				(width 0.1524)
				(type default)
			)
			(layer "B.SilkS")
		)
		(fp_line
			(start 8.9662 1.1684)
			(end 8.9662 -3.6068)
			(stroke
				(width 0.1524)
				(type default)
			)
			(layer "B.SilkS")
		)
		(fp_line
			(start -8.9662 -3.6068)
			(end -8.9662 1.1684)
			(stroke
				(width 0.1524)
				(type default)
			)
			(layer "B.SilkS")
		)
		(fp_line
			(start 8.9662 -3.6068)
			(end -8.9662 -3.6068)
			(stroke
				(width 0.1524)
				(type default)
			)
			(layer "B.SilkS")
		)
		(fp_line
			(start -6.5659 -3.6957)
			(end -7.4549 -3.6957)
			(stroke
				(width 0.3302)
				(type default)
			)
			(layer "B.SilkS")
		)
		(fp_poly
			(pts
				(xy -7.018528 -3.679444) (xy -7.653528 -4.314444) (xy -6.383528 -4.314444)
			)
			(stroke
				(width 0)
				(type default)
			)
			(fill yes)
			(layer "B.SilkS")
		)
		(fp_poly
			(pts
				(xy 3.7592 2.0574) (xy 3.7592 1.1684) (xy 7.690358 1.1684) (xy 7.690358 -1.546606) (xy -7.690358 -1.546606)
				(xy -7.690358 1.1684) (xy -3.7592 1.1684) (xy -3.7592 2.0574)
			)
			(stroke
				(width 0)
				(type default)
			)
			(fill yes)
			(layer "B.SilkS")
		)
		(fp_poly
			(pts
				(xy 3.5052 1.8034) (xy -3.5052 1.8034) (xy -3.5052 0.762) (xy -8.6995 0.762) (xy -8.6995 -2.6416)
				(xy -7.0993 -2.6416) (xy -7.0993 -3.1496) (xy 7.0993 -3.1496) (xy 7.0993 -2.6416) (xy 8.6995 -2.6416)
				(xy 8.6995 0.762) (xy 3.5052 0.762)
			)
			(stroke
				(width 0)
				(type default)
			)
			(fill no)
			(layer "B.CrtYd")
		)
		(fp_poly
			(pts
				(xy 4.0132 2.3114) (xy 4.0132 1.4224) (xy 9.2202 1.4224) (xy 9.2202 -3.8608) (xy -9.2202 -3.8608)
				(xy -9.2202 -0.00635) (xy -8.6995 -0.00635) (xy -8.6995 -2.6416) (xy -7.0993 -2.6416) (xy -7.0993 -3.1496)
				(xy 7.0993 -3.1496) (xy 7.0993 -2.6416) (xy 8.6995 -2.6416) (xy 8.6995 0.762) (xy 3.5052 0.762)
				(xy 3.5052 1.8034) (xy -3.5052 1.8034) (xy -3.5052 0.762) (xy -8.6995 0.762) (xy -8.6995 0.00635)
				(xy -9.2202 0.00635) (xy -9.2202 1.4224) (xy -4.0132 1.4224) (xy -4.0132 2.3114)
			)
			(stroke
				(width 0)
				(type default)
			)
			(fill no)
			(layer "B.CrtYd")
		)
		(fp_poly
			(pts
				(xy 4.0132 2.3114) (xy 4.0132 1.4224) (xy 9.2202 1.4224) (xy 9.2202 -3.8608) (xy -9.2202 -3.8608)
				(xy -9.2202 1.4224) (xy -4.0132 1.4224) (xy -4.0132 2.3114)
			)
			(stroke
				(width 0)
				(type default)
			)
			(fill no)
			(layer "B.Fab")
		)
		(pad "1" smd rect
			(at -6.999986 -2.549906 90)
			(size 0.6096 1.6002)
			(layers "B.Cu" "B.Mask" "B.Paste")
			(net "P5V")
		)
		(pad "2" smd rect
			(at -5.999988 -2.549906 90)
			(size 0.6096 1.6002)
			(layers "B.Cu" "B.Mask" "B.Paste")
			(net "HBA_PRSNT0_N")
		)
		(pad "3" smd rect
			(at -4.99999 -2.549906 90)
			(size 0.6096 1.6002)
			(layers "B.Cu" "B.Mask" "B.Paste")
			(net "HBA_PRSNT1_N")
		)
		(pad "4" smd rect
			(at -3.999992 -2.549906 90)
			(size 0.6096 1.6002)
			(layers "B.Cu" "B.Mask" "B.Paste")
			(net "HBA_PRSNT2_N")
		)
		(pad "5" smd rect
			(at -2.999994 -2.549906 90)
			(size 0.6096 1.6002)
			(layers "B.Cu" "B.Mask" "B.Paste")
			(net "HBA_PRSNT3_N")
		)
		(pad "6" smd rect
			(at -1.999996 -2.549906 90)
			(size 0.6096 1.6002)
			(layers "B.Cu" "B.Mask" "B.Paste")
			(net "GND")
		)
		(pad "7" smd rect
			(at -0.999998 -2.549906 90)
			(size 0.6096 1.6002)
			(layers "B.Cu" "B.Mask" "B.Paste")
			(net "GND")
		)
		(pad "8" smd rect
			(at 0 -2.549906 90)
			(size 0.6096 1.6002)
			(layers "B.Cu" "B.Mask" "B.Paste")
			(net "GND")
		)
		(pad "9" smd rect
			(at 0.999998 -2.549906 90)
			(size 0.6096 1.6002)
			(layers "B.Cu" "B.Mask" "B.Paste")
			(net "HDD_ACT_LED0")
		)
		(pad "10" smd rect
			(at 1.999996 -2.549906 90)
			(size 0.6096 1.6002)
			(layers "B.Cu" "B.Mask" "B.Paste")
			(net "HDD_ACT_LED1")
		)
		(pad "11" smd rect
			(at 2.999994 -2.549906 90)
			(size 0.6096 1.6002)
			(layers "B.Cu" "B.Mask" "B.Paste")
			(net "HDD_ACT_LED2")
		)
		(pad "12" smd rect
			(at 3.999992 -2.549906 90)
			(size 0.6096 1.6002)
			(layers "B.Cu" "B.Mask" "B.Paste")
			(net "HDD_ACT_LED3")
		)
		(pad "13" smd rect
			(at 4.99999 -2.549906 90)
			(size 0.6096 1.6002)
			(layers "B.Cu" "B.Mask" "B.Paste")
			(net "GND")
		)
		(pad "14" smd rect
			(at 5.999988 -2.549906 90)
			(size 0.6096 1.6002)
			(layers "B.Cu" "B.Mask" "B.Paste")
			(net "GND")
		)
		(pad "15" smd rect
			(at 6.999986 -2.549906 90)
			(size 0.6096 1.6002)
			(layers "B.Cu" "B.Mask" "B.Paste")
			(net "GND")
		)
		(pad "PTH1" smd rect
			(at -8.299958 0 90)
			(size 0.8128 1.8034)
			(layers "B.Cu" "B.Mask" "B.Paste")
			(net "GND")
		)
		(pad "PTH2" smd rect
			(at 8.299958 0 90)
			(size 0.8128 1.8034)
			(layers "B.Cu" "B.Mask" "B.Paste")
			(net "GND")
		)
	)
	(footprint ""
		(layer "B.Cu")
		(at 88.552274 -11.316716 90)
		(property "Reference" "U12"
			(at 0 0 90)
			(layer "B.SilkS")
			(hide yes)
			(effects
				(font
					(size 1.27 1.27)
				)
				(justify mirror)
			)
		)
		(property "Value" "P2003EVG-GP"
			(at 0 -11.1252 90)
			(unlocked yes)
			(layer "B.Fab")
			(hide yes)
			(effects
				(font
					(size 1.016 1.016)
					(thickness 0.1524)
				)
				(justify mirror)
			)
		)
		(property "Device Type" "SOIC8H79"
			(at 0 -12.6492 90)
			(unlocked yes)
			(layer "B.Fab")
			(hide yes)
			(effects
				(font
					(size 1.016 1.016)
					(thickness 0.1524)
				)
				(justify mirror)
			)
		)
		(duplicate_pad_numbers_are_jumpers no)
		(fp_line
			(start 2.7432 -1.4224)
			(end 2.7432 1.4224)
			(stroke
				(width 0.1524)
				(type default)
			)
			(layer "B.SilkS")
		)
		(fp_line
			(start -2.1336 -1.4224)
			(end 2.7432 -1.4224)
			(stroke
				(width 0.1524)
				(type default)
			)
			(layer "B.SilkS")
		)
		(fp_line
			(start 2.7432 -0.508)
			(end 2.2352 0)
			(stroke
				(width 0.1524)
				(type default)
			)
			(layer "B.SilkS")
		)
		(fp_line
			(start 2.2352 0)
			(end 2.7432 0.508)
			(stroke
				(width 0.1524)
				(type default)
			)
			(layer "B.SilkS")
		)
		(fp_line
			(start 2.7432 1.4224)
			(end -2.1336 1.4224)
			(stroke
				(width 0.1524)
				(type default)
			)
			(layer "B.SilkS")
		)
		(fp_line
			(start -2.1336 1.4224)
			(end -2.1336 -1.4224)
			(stroke
				(width 0.1524)
				(type default)
			)
			(layer "B.SilkS")
		)
		(fp_line
			(start 2.6162 3.429)
			(end 2.6162 1.4732)
			(stroke
				(width 0.4064)
				(type default)
			)
			(layer "B.SilkS")
		)
		(fp_poly
			(pts
				(xy -2.2098 -1.4224) (xy -2.2098 1.4224) (xy 2.2225 1.4224) (xy 2.2225 -1.4224)
			)
			(stroke
				(width 0)
				(type default)
			)
			(fill yes)
			(layer "B.SilkS")
		)
		(fp_rect
			(start 2.4511 2.9972)
			(end -2.4511 -2.9972)
			(stroke
				(width 0)
				(type default)
			)
			(fill no)
			(layer "B.CrtYd")
		)
		(fp_poly
			(pts
				(xy 2.8194 3.6322) (xy 2.8194 -3.6322) (xy -2.8194 -3.6322) (xy -2.8194 -2.2987) (xy -2.4511 -2.2987)
				(xy -2.4511 -2.9972) (xy 2.4511 -2.9972) (xy 2.4511 2.9972) (xy -2.4511 2.9972) (xy -2.4511 -2.286)
				(xy -2.8194 -2.286) (xy -2.8194 3.6322)
			)
			(stroke
				(width 0)
				(type default)
			)
			(fill no)
			(layer "B.CrtYd")
		)
		(fp_rect
			(start 2.8194 3.6322)
			(end -2.8194 -3.6322)
			(stroke
				(width 0)
				(type default)
			)
			(fill no)
			(layer "B.Fab")
		)
		(pad "1" smd rect
			(at 1.905 2.54 270)
			(size 0.635 1.651)
			(layers "B.Cu" "B.Mask" "B.Paste")
			(net "P12V")
		)
		(pad "2" smd rect
			(at 0.635 2.54 270)
			(size 0.635 1.651)
			(layers "B.Cu" "B.Mask" "B.Paste")
			(net "P12V")
		)
		(pad "3" smd rect
			(at -0.635 2.54 270)
			(size 0.635 1.651)
			(layers "B.Cu" "B.Mask" "B.Paste")
			(net "P12V")
		)
		(pad "4" smd rect
			(at -1.905 2.54 270)
			(size 0.635 1.651)
			(layers "B.Cu" "B.Mask" "B.Paste")
			(net "SW_SW_L_N_0")
		)
		(pad "5" smd rect
			(at -1.905 -2.54 270)
			(size 0.635 1.651)
			(layers "B.Cu" "B.Mask" "B.Paste")
			(net "P12V_SW_L")
		)
		(pad "6" smd rect
			(at -0.635 -2.54 270)
			(size 0.635 1.651)
			(layers "B.Cu" "B.Mask" "B.Paste")
			(net "P12V_SW_L")
		)
		(pad "7" smd rect
			(at 0.635 -2.54 270)
			(size 0.635 1.651)
			(layers "B.Cu" "B.Mask" "B.Paste")
			(net "P12V_SW_L")
		)
		(pad "8" smd rect
			(at 1.905 -2.54 270)
			(size 0.635 1.651)
			(layers "B.Cu" "B.Mask" "B.Paste")
			(net "P12V_SW_L")
		)
	)
	(footprint ""
		(layer "B.Cu")
		(at 77.1906 -9.1948)
		(property "Reference" "U17"
			(at 0 0 0)
			(layer "B.SilkS")
			(hide yes)
			(effects
				(font
					(size 1.27 1.27)
				)
				(justify mirror)
			)
		)
		(property "Value" "SN74LVC1G08DCKR-GP"
			(at 2.3368 -8.6868 0)
			(unlocked yes)
			(layer "B.Fab")
			(hide yes)
			(effects
				(font
					(size 1.016 1.016)
					(thickness 0.1524)
				)
				(justify mirror)
			)
		)
		(property "Device Type" "SC70-5H44"
			(at 2.3114 -10.414 0)
			(unlocked yes)
			(layer "B.Fab")
			(hide yes)
			(effects
				(font
					(size 1.016 1.016)
					(thickness 0.1524)
				)
				(justify mirror)
			)
		)
		(duplicate_pad_numbers_are_jumpers no)
		(fp_line
			(start -1.3843 -1.8034)
			(end -1.3843 -1.1176)
			(stroke
				(width 0.3302)
				(type default)
			)
			(layer "B.SilkS")
		)
		(fp_line
			(start -1.27 -1.7018)
			(end -1.27 1.7018)
			(stroke
				(width 0.1524)
				(type default)
			)
			(layer "B.SilkS")
		)
		(fp_line
			(start -1.27 1.7018)
			(end 1.27 1.7018)
			(stroke
				(width 0.1524)
				(type default)
			)
			(layer "B.SilkS")
		)
		(fp_line
			(start -0.6604 -1.8034)
			(end -1.3843 -1.8034)
			(stroke
				(width 0.3302)
				(type default)
			)
			(layer "B.SilkS")
		)
		(fp_line
			(start 1.27 -1.7018)
			(end -1.27 -1.7018)
			(stroke
				(width 0.1524)
				(type default)
			)
			(layer "B.SilkS")
		)
		(fp_line
			(start 1.27 1.7018)
			(end 1.27 -1.7018)
			(stroke
				(width 0.1524)
				(type default)
			)
			(layer "B.SilkS")
		)
		(fp_rect
			(start 1.524 1.9558)
			(end -1.524 -1.9558)
			(stroke
				(width 0)
				(type default)
			)
			(fill no)
			(layer "B.CrtYd")
		)
		(fp_poly
			(pts
				(xy 1.524 -1.9558) (xy -1.524 -1.9558) (xy -1.524 1.9558) (xy 1.524 1.9558)
			)
			(stroke
				(width 0)
				(type default)
			)
			(fill no)
			(layer "B.Fab")
		)
		(pad "1" smd rect
			(at -0.65024 -0.8255 180)
			(size 0.4064 1.2192)
			(layers "B.Cu" "B.Mask" "B.Paste")
			(net "HBA_PRSNT2_N")
		)
		(pad "2" smd rect
			(at 0 -0.8255 180)
			(size 0.4064 1.2192)
			(layers "B.Cu" "B.Mask" "B.Paste")
			(net "HBA_PRSNT3_N")
		)
		(pad "3" smd rect
			(at 0.65024 -0.8255 180)
			(size 0.4064 1.2192)
			(layers "B.Cu" "B.Mask" "B.Paste")
			(net "GND")
		)
		(pad "4" smd rect
			(at 0.65024 0.8255 180)
			(size 0.4064 1.2192)
			(layers "B.Cu" "B.Mask" "B.Paste")
			(net "PWR_EN_L")
		)
		(pad "5" smd rect
			(at -0.65024 0.8255 180)
			(size 0.4064 1.2192)
			(layers "B.Cu" "B.Mask" "B.Paste")
			(net "P3V3")
		)
	)
	(footprint ""
		(layer "B.Cu")
		(at 78.613 -34.798 180)
		(property "Reference" "U8"
			(at 0 0 0)
			(layer "B.SilkS")
			(hide yes)
			(effects
				(font
					(size 1.27 1.27)
				)
				(justify mirror)
			)
		)
		(property "Value" "DMN63D1LDW-7-GP"
			(at 2.3622 -8.2042 180)
			(unlocked yes)
			(layer "B.Fab")
			(hide yes)
			(effects
				(font
					(size 1.016 1.016)
					(thickness 0.1524)
				)
				(justify mirror)
			)
		)
		(property "Device Type" "SOT-363H44"
			(at 2.3622 -10.1092 180)
			(unlocked yes)
			(layer "B.Fab")
			(hide yes)
			(effects
				(font
					(size 1.016 1.016)
					(thickness 0.1524)
				)
				(justify mirror)
			)
		)
		(duplicate_pad_numbers_are_jumpers no)
		(fp_line
			(start 1.4478 1.7018)
			(end -1.4478 1.7018)
			(stroke
				(width 0.1524)
				(type default)
			)
			(layer "B.SilkS")
		)
		(fp_line
			(start 1.4478 -1.7018)
			(end 1.4478 1.7018)
			(stroke
				(width 0.1524)
				(type default)
			)
			(layer "B.SilkS")
		)
		(fp_line
			(start 1.27 1.524)
			(end 1.27 0.6604)
			(stroke
				(width 0.4826)
				(type default)
			)
			(layer "B.SilkS")
		)
		(fp_line
			(start -1.4478 1.7018)
			(end -1.4478 -1.7018)
			(stroke
				(width 0.1524)
				(type default)
			)
			(layer "B.SilkS")
		)
		(fp_line
			(start -1.4478 -1.7018)
			(end 1.4478 -1.7018)
			(stroke
				(width 0.1524)
				(type default)
			)
			(layer "B.SilkS")
		)
		(fp_poly
			(pts
				(xy 1.524 -1.778) (xy -1.524 -1.778) (xy -1.524 1.778) (xy 1.524 1.778)
			)
			(stroke
				(width 0)
				(type default)
			)
			(fill no)
			(layer "B.CrtYd")
		)
		(fp_poly
			(pts
				(xy 1.524 -1.778) (xy -1.524 -1.778) (xy -1.524 1.778) (xy 1.524 1.778)
			)
			(stroke
				(width 0)
				(type default)
			)
			(fill no)
			(layer "B.Fab")
		)
		(pad "1" smd rect
			(at 0.65024 0.9398)
			(size 0.4064 1.016)
			(layers "B.Cu" "B.Mask" "B.Paste")
			(net "GND")
		)
		(pad "2" smd rect
			(at 0 0.9398)
			(size 0.4064 1.016)
			(layers "B.Cu" "B.Mask" "B.Paste")
			(net "PWR_EN_R_N")
		)
		(pad "3" smd rect
			(at -0.65024 0.9398)
			(size 0.4064 1.016)
			(layers "B.Cu" "B.Mask" "B.Paste")
			(net "SW_SW_R_0")
		)
		(pad "4" smd rect
			(at -0.65024 -0.9398)
			(size 0.4064 1.016)
			(layers "B.Cu" "B.Mask" "B.Paste")
			(net "GND")
		)
		(pad "5" smd rect
			(at 0 -0.9398)
			(size 0.4064 1.016)
			(layers "B.Cu" "B.Mask" "B.Paste")
			(net "PWR_EN_D_0")
		)
		(pad "6" smd rect
			(at 0.65024 -0.9398)
			(size 0.4064 1.016)
			(layers "B.Cu" "B.Mask" "B.Paste")
			(net "PWR_EN_D_0")
		)
	)
	(footprint ""
		(layer "B.Cu")
		(at 80.3656 -9.3218)
		(property "Reference" "U18"
			(at 0 0 0)
			(layer "B.SilkS")
			(hide yes)
			(effects
				(font
					(size 1.27 1.27)
				)
				(justify mirror)
			)
		)
		(property "Value" "ADM1085AKSZ-GP"
			(at 2.3622 -8.2042 0)
			(unlocked yes)
			(layer "B.Fab")
			(hide yes)
			(effects
				(font
					(size 1.016 1.016)
					(thickness 0.1524)
				)
				(justify mirror)
			)
		)
		(property "Device Type" "SC70-6H44"
			(at 2.3622 -10.1092 0)
			(unlocked yes)
			(layer "B.Fab")
			(hide yes)
			(effects
				(font
					(size 1.016 1.016)
					(thickness 0.1524)
				)
				(justify mirror)
			)
		)
		(duplicate_pad_numbers_are_jumpers no)
		(fp_line
			(start -1.4478 -1.7018)
			(end 1.4478 -1.7018)
			(stroke
				(width 0.1524)
				(type default)
			)
			(layer "B.SilkS")
		)
		(fp_line
			(start -1.4478 1.7018)
			(end -1.4478 -1.7018)
			(stroke
				(width 0.1524)
				(type default)
			)
			(layer "B.SilkS")
		)
		(fp_line
			(start 0.5715 1.7907)
			(end 1.5494 1.7907)
			(stroke
				(width 0.3302)
				(type default)
			)
			(layer "B.SilkS")
		)
		(fp_line
			(start 1.4478 -1.7018)
			(end 1.4478 1.7018)
			(stroke
				(width 0.1524)
				(type default)
			)
			(layer "B.SilkS")
		)
		(fp_line
			(start 1.4478 1.7018)
			(end -1.4478 1.7018)
			(stroke
				(width 0.1524)
				(type default)
			)
			(layer "B.SilkS")
		)
		(fp_line
			(start 1.5494 1.7907)
			(end 1.5494 0.8255)
			(stroke
				(width 0.3302)
				(type default)
			)
			(layer "B.SilkS")
		)
		(fp_poly
			(pts
				(xy 0.6604 1.7272) (xy 1.016 2.0828) (xy 0.3048 2.0828)
			)
			(stroke
				(width 0)
				(type default)
			)
			(fill yes)
			(layer "B.SilkS")
		)
		(fp_poly
			(pts
				(xy 1.524 -1.778) (xy -1.524 -1.778) (xy -1.524 1.778) (xy 1.524 1.778)
			)
			(stroke
				(width 0)
				(type default)
			)
			(fill no)
			(layer "B.CrtYd")
		)
		(fp_poly
			(pts
				(xy 1.524 -1.778) (xy -1.524 -1.778) (xy -1.524 1.778) (xy 1.524 1.778)
			)
			(stroke
				(width 0)
				(type default)
			)
			(fill no)
			(layer "B.Fab")
		)
		(pad "1" smd rect
			(at 0.65024 0.9398 180)
			(size 0.4064 1.016)
			(layers "B.Cu" "B.Mask" "B.Paste")
			(net "ENIN_P1")
		)
		(pad "2" smd rect
			(at 0 0.9398 180)
			(size 0.4064 1.016)
			(layers "B.Cu" "B.Mask" "B.Paste")
			(net "GND")
		)
		(pad "3" smd rect
			(at -0.65024 0.9398 180)
			(size 0.4064 1.016)
			(layers "B.Cu" "B.Mask" "B.Paste")
			(net "VIN_P3")
		)
		(pad "4" smd rect
			(at -0.65024 -0.9398 180)
			(size 0.4064 1.016)
			(layers "B.Cu" "B.Mask" "B.Paste")
			(net "PWR_EN_L_DELAY")
		)
		(pad "5" smd rect
			(at 0 -0.9398 180)
			(size 0.4064 1.016)
			(layers "B.Cu" "B.Mask" "B.Paste")
			(net "CEXT_P5")
		)
		(pad "6" smd rect
			(at 0.65024 -0.9398 180)
			(size 0.4064 1.016)
			(layers "B.Cu" "B.Mask" "B.Paste")
			(net "P3V3")
		)
	)
)
